(kicad_pcb
	(version 20260206)
	(generator "pcbnew")
	(generator_version "10.0")
	(general
		(thickness 1.6)
		(legacy_teardrops no)
	)
	(paper "A4")
	(title_block
		(title "Bryce Canyon_IOM_IOC_16318-2_OCP.brd")
		(comment 1 "Bryce Canyon / footprints 1554-1560 of 1605")
	)
	(layers
		(0 "F.Cu" signal "TOP")
		(4 "In1.Cu" signal "L2GND")
		(6 "In2.Cu" signal "L3")
		(8 "In3.Cu" signal "L4VCC")
		(10 "In4.Cu" signal "L5VCC")
		(12 "In5.Cu" signal "L6")
		(14 "In6.Cu" signal "L7GND")
		(2 "B.Cu" signal "BOTTOM")
		(9 "F.Adhes" user "F.Adhesive")
		(11 "B.Adhes" user "B.Adhesive")
		(13 "F.Paste" user "Package Geometry/Pastemask Top")
		(15 "B.Paste" user "Package Geometry/Pastemask Bottom")
		(5 "F.SilkS" user "Ref Des/Silkscreen Top")
		(7 "B.SilkS" user "Ref Des/Silkscreen Bottom")
		(1 "F.Mask" user "Board Geometry/Soldermask Top")
		(3 "B.Mask" user "Board Geometry/Soldermask Bottom")
		(17 "Dwgs.User" user "User.Drawings")
		(19 "Cmts.User" user "User.Comments")
		(21 "Eco1.User" user "User.Eco1")
		(23 "Eco2.User" user "User.Eco2")
		(25 "Edge.Cuts" user "Board Geometry/Outline")
		(27 "Margin" user)
		(31 "F.CrtYd" user "Package Geometry/Place Bound Top")
		(29 "B.CrtYd" user "Package Geometry/Place Bound Bottom")
		(35 "F.Fab" user "Ref Des/Assembly Top")
		(33 "B.Fab" user "Ref Des/Assembly Bottom")
	)
	(footprint ""
		(layer "B.Cu")
		(at 199.86752 -66.29146)
		(property "Reference" "C381"
			(at 0 0 0)
			(layer "B.SilkS")
			(hide yes)
			(effects
				(font
					(size 1.27 1.27)
				)
				(justify mirror)
			)
		)
		(property "Value" "SCD1U6D3V1KX-GP"
			(at 2.8321 -1.7399 0)
			(unlocked yes)
			(layer "B.Fab")
			(hide yes)
			(effects
				(font
					(size 1.016 1.016)
					(thickness 0.1524)
				)
				(justify mirror)
			)
		)
		(property "Device Type" "C0201H13"
			(at 2.8321 -3.2639 0)
			(unlocked yes)
			(layer "B.Fab")
			(hide yes)
			(effects
				(font
					(size 1.016 1.016)
					(thickness 0.1524)
				)
				(justify mirror)
			)
		)
		(duplicate_pad_numbers_are_jumpers no)
		(fp_rect
			(start 0.2794 0.6477)
			(end -0.2794 -0.6477)
			(stroke
				(width 0)
				(type default)
			)
			(fill no)
			(layer "B.CrtYd")
		)
		(fp_rect
			(start 0.2794 0.6477)
			(end -0.2794 -0.6477)
			(stroke
				(width 0)
				(type default)
			)
			(fill no)
			(layer "B.Fab")
		)
		(pad "1" smd custom
			(at 0 -0.2794 180)
			(size 0.0762 0.0762)
			(layers "B.Cu" "B.Mask" "B.Paste")
			(net "SAS0_AVDD")
			(options
				(clearance outline)
				(anchor circle)
			)
			(primitives
				(gr_poly
					(pts
						(arc
							(start 0.1524 0.127)
							(mid 0.137521 0.162921)
							(end 0.1016 0.1778)
						)
						(arc
							(start -0.1016 0.1778)
							(mid -0.137521 0.162921)
							(end -0.1524 0.127)
						)
						(arc
							(start -0.1524 -0.127)
							(mid -0.137521 -0.162921)
							(end -0.1016 -0.1778)
						)
						(arc
							(start 0.1016 -0.1778)
							(mid 0.137521 -0.162921)
							(end 0.1524 -0.127)
						)
					)
					(width 0)
					(fill yes)
				)
			)
		)
		(pad "2" smd custom
			(at 0 0.2794 180)
			(size 0.0762 0.0762)
			(layers "B.Cu" "B.Mask" "B.Paste")
			(net "GND")
			(options
				(clearance outline)
				(anchor circle)
			)
			(primitives
				(gr_poly
					(pts
						(arc
							(start 0.1524 0.127)
							(mid 0.137521 0.162921)
							(end 0.1016 0.1778)
						)
						(arc
							(start -0.1016 0.1778)
							(mid -0.137521 0.162921)
							(end -0.1524 0.127)
						)
						(arc
							(start -0.1524 -0.127)
							(mid -0.137521 -0.162921)
							(end -0.1016 -0.1778)
						)
						(arc
							(start 0.1016 -0.1778)
							(mid 0.137521 -0.162921)
							(end 0.1524 -0.127)
						)
					)
					(width 0)
					(fill yes)
				)
			)
		)
	)
	(footprint ""
		(layer "B.Cu")
		(at 98.9584 -177.9778 90)
		(property "Reference" "C41"
			(at 0 0 90)
			(layer "B.SilkS")
			(hide yes)
			(effects
				(font
					(size 1.27 1.27)
				)
				(justify mirror)
			)
		)
		(property "Value" "SCD1U16V2KX-3GP"
			(at -1.1811 -2.7051 90)
			(unlocked yes)
			(layer "B.Fab")
			(hide yes)
			(effects
				(font
					(size 1.016 1.016)
					(thickness 0.1524)
				)
				(justify mirror)
			)
		)
		(property "Device Type" "C402H22"
			(at -1.1811 -4.2291 90)
			(unlocked yes)
			(layer "B.Fab")
			(hide yes)
			(effects
				(font
					(size 1.016 1.016)
					(thickness 0.1524)
				)
				(justify mirror)
			)
		)
		(duplicate_pad_numbers_are_jumpers no)
		(fp_rect
			(start 0.4318 0.9525)
			(end -0.4318 -0.9525)
			(stroke
				(width 0)
				(type default)
			)
			(fill no)
			(layer "B.CrtYd")
		)
		(fp_rect
			(start 0.4318 0.9525)
			(end -0.4318 -0.9525)
			(stroke
				(width 0)
				(type default)
			)
			(fill no)
			(layer "B.Fab")
		)
		(pad "1" smd custom
			(at 0 -0.4445 270)
			(size 0.1524 0.1524)
			(layers "B.Cu" "B.Mask" "B.Paste")
			(net "P3V3_STBY")
			(options
				(clearance outline)
				(anchor circle)
			)
			(primitives
				(gr_poly
					(pts
						(arc
							(start 0.3048 0.2032)
							(mid 0.275042 0.275042)
							(end 0.2032 0.3048)
						)
						(arc
							(start -0.2032 0.3048)
							(mid -0.275042 0.275042)
							(end -0.3048 0.2032)
						)
						(arc
							(start -0.3048 -0.2032)
							(mid -0.275042 -0.275042)
							(end -0.2032 -0.3048)
						)
						(arc
							(start 0.2032 -0.3048)
							(mid 0.275042 -0.275042)
							(end 0.3048 -0.2032)
						)
					)
					(width 0)
					(fill yes)
				)
			)
		)
		(pad "2" smd custom
			(at 0 0.4445 270)
			(size 0.1524 0.1524)
			(layers "B.Cu" "B.Mask" "B.Paste")
			(net "GND")
			(options
				(clearance outline)
				(anchor circle)
			)
			(primitives
				(gr_poly
					(pts
						(arc
							(start 0.3048 0.2032)
							(mid 0.275042 0.275042)
							(end 0.2032 0.3048)
						)
						(arc
							(start -0.2032 0.3048)
							(mid -0.275042 0.275042)
							(end -0.3048 0.2032)
						)
						(arc
							(start -0.3048 -0.2032)
							(mid -0.275042 -0.275042)
							(end -0.2032 -0.3048)
						)
						(arc
							(start 0.2032 -0.3048)
							(mid 0.275042 -0.275042)
							(end 0.3048 -0.2032)
						)
					)
					(width 0)
					(fill yes)
				)
			)
		)
	)
	(footprint ""
		(layer "B.Cu")
		(at 50.086514 -161.261552)
		(property "Reference" "R323"
			(at 0 0 0)
			(layer "B.SilkS")
			(hide yes)
			(effects
				(font
					(size 1.27 1.27)
				)
				(justify mirror)
			)
		)
		(property "Value" "4K7R2F-GP"
			(at -0.064008 -3.993896 0)
			(unlocked yes)
			(layer "B.Fab")
			(hide yes)
			(effects
				(font
					(size 1.016 1.016)
					(thickness 0.1524)
				)
				(justify mirror)
			)
		)
		(property "Device Type" "R402H16"
			(at -0.064008 -5.517896 0)
			(unlocked yes)
			(layer "B.Fab")
			(hide yes)
			(effects
				(font
					(size 1.016 1.016)
					(thickness 0.1524)
				)
				(justify mirror)
			)
		)
		(duplicate_pad_numbers_are_jumpers no)
		(fp_line
			(start -0.508 -0.9398)
			(end 0.508 -0.9398)
			(stroke
				(width 0.1524)
				(type default)
			)
			(layer "B.SilkS")
		)
		(fp_line
			(start 0.508 -0.9398)
			(end 0.508 0.9398)
			(stroke
				(width 0.1524)
				(type default)
			)
			(layer "B.SilkS")
		)
		(fp_rect
			(start 0.508 0.9398)
			(end -0.508 -0.9398)
			(stroke
				(width 0)
				(type default)
			)
			(fill no)
			(layer "B.CrtYd")
		)
		(fp_rect
			(start 0.508 0.9398)
			(end -0.508 -0.9398)
			(stroke
				(width 0)
				(type default)
			)
			(fill no)
			(layer "B.Fab")
		)
		(pad "1" smd custom
			(at 0 -0.4445 180)
			(size 0.1397 0.1397)
			(layers "B.Cu" "B.Mask" "B.Paste")
			(net "GND")
			(options
				(clearance outline)
				(anchor circle)
			)
			(primitives
				(gr_poly
					(pts
						(arc
							(start -0.1778 0.2794)
							(mid -0.249642 0.249642)
							(end -0.2794 0.1778)
						)
						(arc
							(start -0.2794 -0.1778)
							(mid -0.249642 -0.249642)
							(end -0.1778 -0.2794)
						)
						(arc
							(start 0.1778 -0.2794)
							(mid 0.249642 -0.249642)
							(end 0.2794 -0.1778)
						)
						(arc
							(start 0.2794 0.1778)
							(mid 0.249642 0.249642)
							(end 0.1778 0.2794)
						)
					)
					(width 0)
					(fill yes)
				)
			)
		)
		(pad "2" smd custom
			(at 0 0.4445 180)
			(size 0.1397 0.1397)
			(layers "B.Cu" "B.Mask" "B.Paste")
			(net "BOARD_REV_1")
			(options
				(clearance outline)
				(anchor circle)
			)
			(primitives
				(gr_poly
					(pts
						(arc
							(start -0.1778 0.2794)
							(mid -0.249642 0.249642)
							(end -0.2794 0.1778)
						)
						(arc
							(start -0.2794 -0.1778)
							(mid -0.249642 -0.249642)
							(end -0.1778 -0.2794)
						)
						(arc
							(start 0.1778 -0.2794)
							(mid 0.249642 -0.249642)
							(end 0.2794 -0.1778)
						)
						(arc
							(start 0.2794 0.1778)
							(mid 0.249642 0.249642)
							(end 0.1778 0.2794)
						)
					)
					(width 0)
					(fill yes)
				)
			)
		)
	)
	(footprint ""
		(layer "B.Cu")
		(at 62.992 -143.7386 90)
		(property "Reference" "R196"
			(at 0 0 90)
			(layer "B.SilkS")
			(hide yes)
			(effects
				(font
					(size 1.27 1.27)
				)
				(justify mirror)
			)
		)
		(property "Value" "2K2R2F-GP"
			(at -0.064008 -3.993896 90)
			(unlocked yes)
			(layer "B.Fab")
			(hide yes)
			(effects
				(font
					(size 1.016 1.016)
					(thickness 0.1524)
				)
				(justify mirror)
			)
		)
		(property "Device Type" "R402H16"
			(at -0.064008 -5.517896 90)
			(unlocked yes)
			(layer "B.Fab")
			(hide yes)
			(effects
				(font
					(size 1.016 1.016)
					(thickness 0.1524)
				)
				(justify mirror)
			)
		)
		(duplicate_pad_numbers_are_jumpers no)
		(fp_line
			(start 0.508 -0.9398)
			(end 0.508 0.9398)
			(stroke
				(width 0.1524)
				(type default)
			)
			(layer "B.SilkS")
		)
		(fp_line
			(start -0.508 -0.9398)
			(end 0.508 -0.9398)
			(stroke
				(width 0.1524)
				(type default)
			)
			(layer "B.SilkS")
		)
		(fp_rect
			(start 0.508 0.9398)
			(end -0.508 -0.9398)
			(stroke
				(width 0)
				(type default)
			)
			(fill no)
			(layer "B.CrtYd")
		)
		(fp_rect
			(start 0.508 0.9398)
			(end -0.508 -0.9398)
			(stroke
				(width 0)
				(type default)
			)
			(fill no)
			(layer "B.Fab")
		)
		(pad "1" smd custom
			(at 0 -0.4445 270)
			(size 0.1397 0.1397)
			(layers "B.Cu" "B.Mask" "B.Paste")
			(net "I2C_EXP_LOC_SDA_OUT")
			(options
				(clearance outline)
				(anchor circle)
			)
			(primitives
				(gr_poly
					(pts
						(arc
							(start -0.1778 0.2794)
							(mid -0.249642 0.249642)
							(end -0.2794 0.1778)
						)
						(arc
							(start -0.2794 -0.1778)
							(mid -0.249642 -0.249642)
							(end -0.1778 -0.2794)
						)
						(arc
							(start 0.1778 -0.2794)
							(mid 0.249642 -0.249642)
							(end 0.2794 -0.1778)
						)
						(arc
							(start 0.2794 0.1778)
							(mid 0.249642 0.249642)
							(end 0.1778 0.2794)
						)
					)
					(width 0)
					(fill yes)
				)
			)
		)
		(pad "2" smd custom
			(at 0 0.4445 270)
			(size 0.1397 0.1397)
			(layers "B.Cu" "B.Mask" "B.Paste")
			(net "P3V3_STBY")
			(options
				(clearance outline)
				(anchor circle)
			)
			(primitives
				(gr_poly
					(pts
						(arc
							(start -0.1778 0.2794)
							(mid -0.249642 0.249642)
							(end -0.2794 0.1778)
						)
						(arc
							(start -0.2794 -0.1778)
							(mid -0.249642 -0.249642)
							(end -0.1778 -0.2794)
						)
						(arc
							(start 0.1778 -0.2794)
							(mid 0.249642 -0.249642)
							(end 0.2794 -0.1778)
						)
						(arc
							(start 0.2794 0.1778)
							(mid 0.249642 0.249642)
							(end 0.1778 0.2794)
						)
					)
					(width 0)
					(fill yes)
				)
			)
		)
	)
	(footprint ""
		(layer "B.Cu")
		(at 25.557226 -143.81099 180)
		(property "Reference" "C70"
			(at 0 0 0)
			(layer "B.SilkS")
			(hide yes)
			(effects
				(font
					(size 1.27 1.27)
				)
				(justify mirror)
			)
		)
		(property "Value" "SCD1U16V2KX-3GP"
			(at -1.1811 -2.7051 180)
			(unlocked yes)
			(layer "B.Fab")
			(hide yes)
			(effects
				(font
					(size 1.016 1.016)
					(thickness 0.1524)
				)
				(justify mirror)
			)
		)
		(property "Device Type" "C402H22"
			(at -1.1811 -4.2291 180)
			(unlocked yes)
			(layer "B.Fab")
			(hide yes)
			(effects
				(font
					(size 1.016 1.016)
					(thickness 0.1524)
				)
				(justify mirror)
			)
		)
		(duplicate_pad_numbers_are_jumpers no)
		(fp_rect
			(start 0.4318 0.9525)
			(end -0.4318 -0.9525)
			(stroke
				(width 0)
				(type default)
			)
			(fill no)
			(layer "B.CrtYd")
		)
		(fp_rect
			(start 0.4318 0.9525)
			(end -0.4318 -0.9525)
			(stroke
				(width 0)
				(type default)
			)
			(fill no)
			(layer "B.Fab")
		)
		(pad "1" smd custom
			(at 0 -0.4445)
			(size 0.1524 0.1524)
			(layers "B.Cu" "B.Mask" "B.Paste")
			(net "GND")
			(options
				(clearance outline)
				(anchor circle)
			)
			(primitives
				(gr_poly
					(pts
						(arc
							(start 0.3048 0.2032)
							(mid 0.275042 0.275042)
							(end 0.2032 0.3048)
						)
						(arc
							(start -0.2032 0.3048)
							(mid -0.275042 0.275042)
							(end -0.3048 0.2032)
						)
						(arc
							(start -0.3048 -0.2032)
							(mid -0.275042 -0.275042)
							(end -0.2032 -0.3048)
						)
						(arc
							(start 0.2032 -0.3048)
							(mid 0.275042 -0.275042)
							(end 0.3048 -0.2032)
						)
					)
					(width 0)
					(fill yes)
				)
			)
		)
		(pad "2" smd custom
			(at 0 0.4445)
			(size 0.1524 0.1524)
			(layers "B.Cu" "B.Mask" "B.Paste")
			(net "P1V2_STBY")
			(options
				(clearance outline)
				(anchor circle)
			)
			(primitives
				(gr_poly
					(pts
						(arc
							(start 0.3048 0.2032)
							(mid 0.275042 0.275042)
							(end 0.2032 0.3048)
						)
						(arc
							(start -0.2032 0.3048)
							(mid -0.275042 0.275042)
							(end -0.3048 0.2032)
						)
						(arc
							(start -0.3048 -0.2032)
							(mid -0.275042 -0.275042)
							(end -0.2032 -0.3048)
						)
						(arc
							(start 0.2032 -0.3048)
							(mid 0.275042 -0.275042)
							(end 0.3048 -0.2032)
						)
					)
					(width 0)
					(fill yes)
				)
			)
		)
	)
	(footprint ""
		(layer "B.Cu")
		(at 197.35546 -72.34428 90)
		(property "Reference" "C360"
			(at 0 0 90)
			(layer "B.SilkS")
			(hide yes)
			(effects
				(font
					(size 1.27 1.27)
				)
				(justify mirror)
			)
		)
		(property "Value" "SCD1U6D3V1KX-GP"
			(at 2.8321 -1.7399 90)
			(unlocked yes)
			(layer "B.Fab")
			(hide yes)
			(effects
				(font
					(size 1.016 1.016)
					(thickness 0.1524)
				)
				(justify mirror)
			)
		)
		(property "Device Type" "C0201H13"
			(at 2.8321 -3.2639 90)
			(unlocked yes)
			(layer "B.Fab")
			(hide yes)
			(effects
				(font
					(size 1.016 1.016)
					(thickness 0.1524)
				)
				(justify mirror)
			)
		)
		(duplicate_pad_numbers_are_jumpers no)
		(fp_rect
			(start 0.2794 0.6477)
			(end -0.2794 -0.6477)
			(stroke
				(width 0)
				(type default)
			)
			(fill no)
			(layer "B.CrtYd")
		)
		(fp_rect
			(start 0.2794 0.6477)
			(end -0.2794 -0.6477)
			(stroke
				(width 0)
				(type default)
			)
			(fill no)
			(layer "B.Fab")
		)
		(pad "1" smd custom
			(at 0 -0.2794 270)
			(size 0.0762 0.0762)
			(layers "B.Cu" "B.Mask" "B.Paste")
			(net "PCE_VDDH")
			(options
				(clearance outline)
				(anchor circle)
			)
			(primitives
				(gr_poly
					(pts
						(arc
							(start 0.1524 0.127)
							(mid 0.137521 0.162921)
							(end 0.1016 0.1778)
						)
						(arc
							(start -0.1016 0.1778)
							(mid -0.137521 0.162921)
							(end -0.1524 0.127)
						)
						(arc
							(start -0.1524 -0.127)
							(mid -0.137521 -0.162921)
							(end -0.1016 -0.1778)
						)
						(arc
							(start 0.1016 -0.1778)
							(mid 0.137521 -0.162921)
							(end 0.1524 -0.127)
						)
					)
					(width 0)
					(fill yes)
				)
			)
		)
		(pad "2" smd custom
			(at 0 0.2794 270)
			(size 0.0762 0.0762)
			(layers "B.Cu" "B.Mask" "B.Paste")
			(net "GND")
			(options
				(clearance outline)
				(anchor circle)
			)
			(primitives
				(gr_poly
					(pts
						(arc
							(start 0.1524 0.127)
							(mid 0.137521 0.162921)
							(end 0.1016 0.1778)
						)
						(arc
							(start -0.1016 0.1778)
							(mid -0.137521 0.162921)
							(end -0.1524 0.127)
						)
						(arc
							(start -0.1524 -0.127)
							(mid -0.137521 -0.162921)
							(end -0.1016 -0.1778)
						)
						(arc
							(start 0.1016 -0.1778)
							(mid 0.137521 -0.162921)
							(end 0.1524 -0.127)
						)
					)
					(width 0)
					(fill yes)
				)
			)
		)
	)
	(footprint ""
		(layer "B.Cu")
		(at 24.456898 -145.973546)
		(property "Reference" "C72"
			(at 0 0 0)
			(layer "B.SilkS")
			(hide yes)
			(effects
				(font
					(size 1.27 1.27)
				)
				(justify mirror)
			)
		)
		(property "Value" "SCD1U16V2KX-3GP"
			(at -1.1811 -2.7051 0)
			(unlocked yes)
			(layer "B.Fab")
			(hide yes)
			(effects
				(font
					(size 1.016 1.016)
					(thickness 0.1524)
				)
				(justify mirror)
			)
		)
		(property "Device Type" "C402H22"
			(at -1.1811 -4.2291 0)
			(unlocked yes)
			(layer "B.Fab")
			(hide yes)
			(effects
				(font
					(size 1.016 1.016)
					(thickness 0.1524)
				)
				(justify mirror)
			)
		)
		(duplicate_pad_numbers_are_jumpers no)
		(fp_rect
			(start 0.4318 0.9525)
			(end -0.4318 -0.9525)
			(stroke
				(width 0)
				(type default)
			)
			(fill no)
			(layer "B.CrtYd")
		)
		(fp_rect
			(start 0.4318 0.9525)
			(end -0.4318 -0.9525)
			(stroke
				(width 0)
				(type default)
			)
			(fill no)
			(layer "B.Fab")
		)
		(pad "1" smd custom
			(at 0 -0.4445 180)
			(size 0.1524 0.1524)
			(layers "B.Cu" "B.Mask" "B.Paste")
			(net "GND")
			(options
				(clearance outline)
				(anchor circle)
			)
			(primitives
				(gr_poly
					(pts
						(arc
							(start 0.3048 0.2032)
							(mid 0.275042 0.275042)
							(end 0.2032 0.3048)
						)
						(arc
							(start -0.2032 0.3048)
							(mid -0.275042 0.275042)
							(end -0.3048 0.2032)
						)
						(arc
							(start -0.3048 -0.2032)
							(mid -0.275042 -0.275042)
							(end -0.2032 -0.3048)
						)
						(arc
							(start 0.2032 -0.3048)
							(mid 0.275042 -0.275042)
							(end 0.3048 -0.2032)
						)
					)
					(width 0)
					(fill yes)
				)
			)
		)
		(pad "2" smd custom
			(at 0 0.4445 180)
			(size 0.1524 0.1524)
			(layers "B.Cu" "B.Mask" "B.Paste")
			(net "P1V2_STBY")
			(options
				(clearance outline)
				(anchor circle)
			)
			(primitives
				(gr_poly
					(pts
						(arc
							(start 0.3048 0.2032)
							(mid 0.275042 0.275042)
							(end 0.2032 0.3048)
						)
						(arc
							(start -0.2032 0.3048)
							(mid -0.275042 0.275042)
							(end -0.3048 0.2032)
						)
						(arc
							(start -0.3048 -0.2032)
							(mid -0.275042 -0.275042)
							(end -0.2032 -0.3048)
						)
						(arc
							(start 0.2032 -0.3048)
							(mid 0.275042 -0.275042)
							(end 0.3048 -0.2032)
						)
					)
					(width 0)
					(fill yes)
				)
			)
		)
	)
)
